# S9S_MB_2U (Grand Teton) — schematic netlist excerpt (pin names and nets, part order shuffled) for the footprints in the layout excerpt that follows; sources: Cadence DE-HDL packaged netlist, KiCad conversion of 03242023_DA0F0TMBIJ0_F0T_Motherboard_J_brd_V01_OCP.brd

R588  Q_RES  33.2 1% CHIP  pkg 0402LF  page 231 : A = SMB_PCIE0_3V3AUX_SCL ; B = SMB_PCIE0_3V3AUX_SCL_R
C1113  Q_CAP  0.01UF 50V 10% X7R  pkg C0402  page 217 : A = P3V3_AUX_FPGA_VCCIO3 ; B = GND

(kicad_pcb
	(version 20260206)
	(generator "pcbnew")
	(generator_version "10.0")
	(general
		(thickness 1.6)
		(legacy_teardrops no)
	)
	(paper "A4")
	(title_block
		(title "03242023_DA0F0TMBIJ0_F0T_Motherboard_J_brd_V01_OCP.brd")
		(comment 1 "Grand Teton / footprints 4337-4338 of 6105")
	)
	(layers
		(0 "F.Cu" signal "TOP")
		(4 "In1.Cu" signal "GND")
		(6 "In2.Cu" signal "IN1")
		(8 "In3.Cu" signal "GND1")
		(10 "In4.Cu" signal "IN2")
		(12 "In5.Cu" signal "GND2")
		(14 "In6.Cu" signal "IN3")
		(16 "In7.Cu" signal "GND3")
		(18 "In8.Cu" signal "VCC")
		(20 "In9.Cu" signal "VCC1")
		(22 "In10.Cu" signal "GND4")
		(24 "In11.Cu" signal "IN4")
		(26 "In12.Cu" signal "GND5")
		(28 "In13.Cu" signal "IN5")
		(30 "In14.Cu" signal "GND6")
		(32 "In15.Cu" signal "IN6")
		(34 "In16.Cu" signal "GND7")
		(2 "B.Cu" signal "BOTTOM")
		(9 "F.Adhes" user "F.Adhesive")
		(11 "B.Adhes" user "B.Adhesive")
		(13 "F.Paste" user "Package Geometry/Pastemask Top")
		(15 "B.Paste" user "Package Geometry/Pastemask Bottom")
		(5 "F.SilkS" user "Ref Des/Silkscreen Top")
		(7 "B.SilkS" user "Ref Des/Silkscreen Bottom")
		(1 "F.Mask" user "Board Geometry/Soldermask Top")
		(3 "B.Mask" user "Board Geometry/Soldermask Bottom")
		(17 "Dwgs.User" user "User.Drawings")
		(19 "Cmts.User" user "User.Comments")
		(21 "Eco1.User" user "User.Eco1")
		(23 "Eco2.User" user "User.Eco2")
		(25 "Edge.Cuts" user "Board Geometry/Outline")
		(27 "Margin" user)
		(31 "F.CrtYd" user "Package Geometry/Place Bound Top")
		(29 "B.CrtYd" user "Package Geometry/Place Bound Bottom")
		(35 "F.Fab" user "Ref Des/Assembly Top")
		(33 "B.Fab" user "Ref Des/Assembly Bottom")
	)
	(footprint ""
		(layer "B.Cu")
		(at 179.755546 -110.975394 -90)
		(property "Reference" "C1113"
			(at 0 0 90)
			(layer "B.SilkS")
			(hide yes)
			(effects
				(font
					(size 1.27 1.27)
				)
				(justify mirror)
			)
		)
		(property "Value" ""
			(at 0 0 90)
			(layer "B.Fab")
			(effects
				(font
					(size 1.27 1.27)
				)
				(justify mirror)
			)
		)
		(duplicate_pad_numbers_are_jumpers no)
		(fp_line
			(start -0.69215 0.2921)
			(end 0.69215 0.2921)
			(stroke
				(width 0.1524)
				(type default)
			)
			(layer "B.SilkS")
		)
		(fp_line
			(start 0.69215 0.2921)
			(end 0.69215 -0.2921)
			(stroke
				(width 0.1524)
				(type default)
			)
			(layer "B.SilkS")
		)
		(fp_line
			(start -0.69215 -0.2921)
			(end -0.69215 0.2921)
			(stroke
				(width 0.1524)
				(type default)
			)
			(layer "B.SilkS")
		)
		(fp_line
			(start 0.69215 -0.2921)
			(end -0.69215 -0.2921)
			(stroke
				(width 0.1524)
				(type default)
			)
			(layer "B.SilkS")
		)
		(fp_line
			(start -0.51435 0.2794)
			(end 0.51435 0.2794)
			(stroke
				(width 0.1)
				(type default)
			)
			(layer "B.Fab")
		)
		(fp_line
			(start 0.51435 0.2794)
			(end 0.51435 -0.2794)
			(stroke
				(width 0.1)
				(type default)
			)
			(layer "B.Fab")
		)
		(fp_line
			(start -0.51435 -0.2794)
			(end -0.51435 0.2794)
			(stroke
				(width 0.1)
				(type default)
			)
			(layer "B.Fab")
		)
		(fp_line
			(start 0.51435 -0.2794)
			(end -0.51435 -0.2794)
			(stroke
				(width 0.1)
				(type default)
			)
			(layer "B.Fab")
		)
		(pad "1" smd circle
			(at 0.40005 0 90)
			(size 0 0)
			(layers "B.Cu" "B.Mask" "B.Paste")
			(net "P3V3_AUX_FPGA_VCCIO3")
		)
		(pad "2" smd circle
			(at -0.40005 0 90)
			(size 0 0)
			(layers "B.Cu" "B.Mask" "B.Paste")
			(net "GND")
		)
		(zone
			(layer "B.Cu")
			(hatch none 0.5)
			(connect_pads
				(clearance 0)
			)
			(min_thickness 0.25)
			(keepout
				(tracks not_allowed)
				(vias allowed)
				(pads allowed)
				(copperpour not_allowed)
				(footprints allowed)
			)
			(placement
				(enabled no)
				(sheetname "")
			)
			(fill
				(thermal_gap 0.5)
				(thermal_bridge_width 0.5)
				(island_removal_mode 0)
			)
			(polygon
				(pts
					(xy 179.667916 -110.784894) (xy 179.60975 -110.876334) (xy 179.60975 -111.075724) (xy 179.667916 -111.165894)
					(xy 179.843176 -111.165894) (xy 179.901596 -111.075724) (xy 179.901596 -110.876334) (xy 179.84343 -110.784894)
				)
			)
		)
	)
	(footprint ""
		(layer "B.Cu")
		(at 157.02788 -9.830308)
		(property "Reference" "R588"
			(at 0 0 0)
			(layer "B.SilkS")
			(hide yes)
			(effects
				(font
					(size 1.27 1.27)
				)
				(justify mirror)
			)
		)
		(property "Value" ""
			(at 0 0 0)
			(layer "B.Fab")
			(effects
				(font
					(size 1.27 1.27)
				)
				(justify mirror)
			)
		)
		(duplicate_pad_numbers_are_jumpers no)
		(fp_line
			(start -0.7874 -0.4064)
			(end -0.7874 0.4064)
			(stroke
				(width 0.1524)
				(type default)
			)
			(layer "B.SilkS")
		)
		(fp_line
			(start -0.7874 0.4064)
			(end 0.7874 0.4064)
			(stroke
				(width 0.1524)
				(type default)
			)
			(layer "B.SilkS")
		)
		(fp_line
			(start 0.7874 -0.4064)
			(end -0.7874 -0.4064)
			(stroke
				(width 0.1524)
				(type default)
			)
			(layer "B.SilkS")
		)
		(fp_line
			(start 0.7874 0.4064)
			(end 0.7874 -0.4064)
			(stroke
				(width 0.1524)
				(type default)
			)
			(layer "B.SilkS")
		)
		(fp_line
			(start -0.67945 -0.3048)
			(end -0.67945 0.3048)
			(stroke
				(width 0.1)
				(type default)
			)
			(layer "B.Fab")
		)
		(fp_line
			(start -0.67945 0.3048)
			(end -0.120396 0.3048)
			(stroke
				(width 0.1)
				(type default)
			)
			(layer "B.Fab")
		)
		(fp_line
			(start -0.12065 -0.3048)
			(end -0.67945 -0.3048)
			(stroke
				(width 0.1)
				(type default)
			)
			(layer "B.Fab")
		)
		(fp_line
			(start -0.12065 -0.2794)
			(end -0.12065 -0.3048)
			(stroke
				(width 0.1)
				(type default)
			)
			(layer "B.Fab")
		)
		(fp_line
			(start -0.120396 0.2794)
			(end 0.12065 0.2794)
			(stroke
				(width 0.1)
				(type default)
			)
			(layer "B.Fab")
		)
		(fp_line
			(start -0.120396 0.3048)
			(end -0.120396 0.2794)
			(stroke
				(width 0.1)
				(type default)
			)
			(layer "B.Fab")
		)
		(fp_line
			(start 0.12065 -0.305054)
			(end 0.12065 -0.2794)
			(stroke
				(width 0.1)
				(type default)
			)
			(layer "B.Fab")
		)
		(fp_line
			(start 0.12065 -0.2794)
			(end -0.12065 -0.2794)
			(stroke
				(width 0.1)
				(type default)
			)
			(layer "B.Fab")
		)
		(fp_line
			(start 0.12065 0.2794)
			(end 0.12065 0.3048)
			(stroke
				(width 0.1)
				(type default)
			)
			(layer "B.Fab")
		)
		(fp_line
			(start 0.12065 0.3048)
			(end 0.67945 0.3048)
			(stroke
				(width 0.1)
				(type default)
			)
			(layer "B.Fab")
		)
		(fp_line
			(start 0.67945 -0.305054)
			(end 0.12065 -0.305054)
			(stroke
				(width 0.1)
				(type default)
			)
			(layer "B.Fab")
		)
		(fp_line
			(start 0.67945 0.3048)
			(end 0.67945 -0.305054)
			(stroke
				(width 0.1)
				(type default)
			)
			(layer "B.Fab")
		)
		(pad "1" smd circle
			(at 0.40005 0 180)
			(size 0 0)
			(layers "B.Cu" "B.Mask" "B.Paste")
			(net "SMB_PCIE0_3V3AUX_SCL")
		)
		(pad "2" smd circle
			(at -0.40005 0 180)
			(size 0 0)
			(layers "B.Cu" "B.Mask" "B.Paste")
			(net "SMB_PCIE0_3V3AUX_SCL_R")
		)
	)
)
